# TIMECARD (Time Appliance Project (Time Card)) — schematic netlist excerpt (pin names and nets, part order shuffled) for the footprints in the layout excerpt that follows; sources: Cadence DE-HDL packaged netlist, KiCad conversion of R4006-B0001-02_R01.brd

R102  RESISTOR  1KOHM 1%  pkg SMC_0402R_H016  page 21 : \1\ = XP5R0V_USB_CONN_DET ; \2\ = UNNAMED_527_RESISTOR_I201_2
C158  CAPACITOR  22UF 10V 20%  pkg SMC_0805R_H057  page 14 : \1\ = XP1R8V_FPGA ; \2\ = SG

(kicad_pcb
	(version 20260206)
	(generator "pcbnew")
	(generator_version "10.0")
	(general
		(thickness 1.6)
		(legacy_teardrops no)
	)
	(paper "A4")
	(title_block
		(title "timecard-production-celestica-r4006 — R4006-B0001-02_R01.brd")
		(comment 1 "Time Appliance Project (Time Card) / footprints 1091-1092 of 1113")
	)
	(layers
		(0 "F.Cu" signal "TOP")
		(4 "In1.Cu" signal "L02_GND1")
		(6 "In2.Cu" signal "L03_SIG1")
		(8 "In3.Cu" signal "L04_GND2")
		(10 "In4.Cu" signal "L05_VCC1")
		(12 "In5.Cu" signal "L06_VCC2")
		(14 "In6.Cu" signal "L07_GND3")
		(16 "In7.Cu" signal "L08_SIG2")
		(18 "In8.Cu" signal "L09_GND4")
		(2 "B.Cu" signal "BOTTOM")
		(9 "F.Adhes" user "F.Adhesive")
		(11 "B.Adhes" user "B.Adhesive")
		(13 "F.Paste" user "Package Geometry/Pastemask Top")
		(15 "B.Paste" user "Package Geometry/Pastemask Bottom")
		(5 "F.SilkS" user "Ref Des/Silkscreen Top")
		(7 "B.SilkS" user "Ref Des/Silkscreen Bottom")
		(1 "F.Mask" user "Board Geometry/Soldermask Top")
		(3 "B.Mask" user "Board Geometry/Soldermask Bottom")
		(17 "Dwgs.User" user "User.Drawings")
		(19 "Cmts.User" user "User.Comments")
		(21 "Eco1.User" user "User.Eco1")
		(23 "Eco2.User" user "User.Eco2")
		(25 "Edge.Cuts" user "Board Geometry/Outline")
		(27 "Margin" user)
		(31 "F.CrtYd" user "Package Geometry/Place Bound Top")
		(29 "B.CrtYd" user "Package Geometry/Place Bound Bottom")
		(35 "F.Fab" user "Ref Des/Assembly Top")
		(33 "B.Fab" user "Ref Des/Assembly Bottom")
	)
	(footprint ""
		(layer "B.Cu")
		(at 92.583 -56.642 180)
		(property "Reference" "C158"
			(at 1.397 1.48463 0)
			(unlocked yes)
			(layer "B.SilkS")
			(effects
				(font
					(size 0.7874 0.5842)
					(thickness 0.1524)
				)
				(justify mirror)
			)
		)
		(property "Value" "VAL*"
			(at -0.0762 3.134106 180)
			(unlocked yes)
			(layer "B.Fab")
			(hide yes)
			(effects
				(font
					(size 0.7874 0.5842)
					(thickness 0.1524)
				)
				(justify mirror)
			)
		)
		(property "Device Type" "CAPACITOR-G107-0F226-CM,22UF,2A"
			(at -0.0508 2.194306 180)
			(unlocked yes)
			(layer "B.Fab")
			(hide yes)
			(effects
				(font
					(size 0.7874 0.5842)
					(thickness 0.1524)
				)
				(justify mirror)
			)
		)
		(property "User Part Number" "PARTNUM*"
			(at -0.1016 5.013706 180)
			(unlocked yes)
			(layer "Cmts.User")
			(hide yes)
			(effects
				(font
					(size 0.7874 0.5842)
					(thickness 0.1524)
				)
				(justify mirror)
			)
		)
		(property "Tolerance" "TOL*"
			(at -0.0762 4.048506 180)
			(unlocked yes)
			(layer "Cmts.User")
			(hide yes)
			(effects
				(font
					(size 0.7874 0.5842)
					(thickness 0.1524)
				)
				(justify mirror)
			)
		)
		(duplicate_pad_numbers_are_jumpers no)
		(fp_line
			(start 1.5748 0.9398)
			(end -1.5748 0.9398)
			(stroke
				(width 0.1)
				(type default)
			)
			(layer "B.SilkS")
		)
		(fp_line
			(start 1.5748 -0.9398)
			(end 1.5748 0.9398)
			(stroke
				(width 0.1)
				(type default)
			)
			(layer "B.SilkS")
		)
		(fp_line
			(start -1.5748 0.9398)
			(end -1.5748 -0.9398)
			(stroke
				(width 0.1)
				(type default)
			)
			(layer "B.SilkS")
		)
		(fp_line
			(start -1.5748 -0.9398)
			(end 1.5748 -0.9398)
			(stroke
				(width 0.1)
				(type default)
			)
			(layer "B.SilkS")
		)
		(fp_rect
			(start -1.5748 -0.9398)
			(end 1.5748 0.9398)
			(stroke
				(width 0)
				(type default)
			)
			(fill no)
			(layer "B.CrtYd")
		)
		(fp_line
			(start 1.016 0.635)
			(end -1.016 0.635)
			(stroke
				(width 0.1)
				(type default)
			)
			(layer "B.Fab")
		)
		(fp_line
			(start 1.016 -0.635)
			(end 1.016 0.635)
			(stroke
				(width 0.1)
				(type default)
			)
			(layer "B.Fab")
		)
		(fp_line
			(start -1.016 0.635)
			(end -1.016 -0.635)
			(stroke
				(width 0.1)
				(type default)
			)
			(layer "B.Fab")
		)
		(fp_line
			(start -1.016 -0.635)
			(end 1.016 -0.635)
			(stroke
				(width 0.1)
				(type default)
			)
			(layer "B.Fab")
		)
		(pad "1" smd rect
			(at 0.8382 0)
			(size 0.9652 1.3716)
			(layers "B.Cu" "B.Mask" "B.Paste")
			(net "XP1R8V_FPGA")
		)
		(pad "2" smd rect
			(at -0.8382 0)
			(size 0.9652 1.3716)
			(layers "B.Cu" "B.Mask" "B.Paste")
			(net "SG")
		)
		(zone
			(layer "B.Cu")
			(hatch none 0.5)
			(connect_pads
				(clearance 0)
			)
			(min_thickness 0.25)
			(keepout
				(tracks allowed)
				(vias not_allowed)
				(pads allowed)
				(copperpour not_allowed)
				(footprints allowed)
			)
			(placement
				(enabled no)
				(sheetname "")
			)
			(fill
				(thermal_gap 0.5)
				(thermal_bridge_width 0.5)
				(island_removal_mode 0)
			)
			(polygon
				(pts
					(xy 92.8116 -56.007) (xy 92.8116 -57.277) (xy 92.3544 -57.277) (xy 92.3544 -56.007)
				)
			)
		)
	)
	(footprint ""
		(layer "B.Cu")
		(at 158.877 -50.513996 -90)
		(property "Reference" "R102"
			(at 7.874 -1.35763 270)
			(unlocked yes)
			(layer "B.SilkS")
			(effects
				(font
					(size 0.7874 0.5842)
					(thickness 0.1524)
				)
				(justify mirror)
			)
		)
		(property "Value" "VAL*"
			(at -0.02032 2.13233 270)
			(unlocked yes)
			(layer "B.Fab")
			(hide yes)
			(effects
				(font
					(size 0.7874 0.5842)
					(thickness 0.1524)
				)
				(justify mirror)
			)
		)
		(property "Device Type" "RESISTOR-G155-11001-01,1KOHM,1%"
			(at -0.008382 1.210564 270)
			(unlocked yes)
			(layer "B.Fab")
			(hide yes)
			(effects
				(font
					(size 0.7874 0.5842)
					(thickness 0.1524)
				)
				(justify mirror)
			)
		)
		(property "User Part Number" "PARTNUM*"
			(at -0.02032 4.024884 270)
			(unlocked yes)
			(layer "Cmts.User")
			(hide yes)
			(effects
				(font
					(size 0.7874 0.5842)
					(thickness 0.1524)
				)
				(justify mirror)
			)
		)
		(property "Tolerance" "TOL*"
			(at -0.044704 3.05435 270)
			(unlocked yes)
			(layer "Cmts.User")
			(hide yes)
			(effects
				(font
					(size 0.7874 0.5842)
					(thickness 0.1524)
				)
				(justify mirror)
			)
		)
		(duplicate_pad_numbers_are_jumpers no)
		(fp_line
			(start -1.143 0.5588)
			(end -1.143 -0.5588)
			(stroke
				(width 0.1)
				(type default)
			)
			(layer "B.SilkS")
		)
		(fp_line
			(start 1.143 0.5588)
			(end -1.143 0.5588)
			(stroke
				(width 0.1)
				(type default)
			)
			(layer "B.SilkS")
		)
		(fp_line
			(start -1.143 -0.5588)
			(end 1.143 -0.5588)
			(stroke
				(width 0.1)
				(type default)
			)
			(layer "B.SilkS")
		)
		(fp_line
			(start 1.143 -0.5588)
			(end 1.143 0.5588)
			(stroke
				(width 0.1)
				(type default)
			)
			(layer "B.SilkS")
		)
		(fp_rect
			(start -1.143 -0.5588)
			(end 1.143 0.5588)
			(stroke
				(width 0)
				(type default)
			)
			(fill no)
			(layer "B.CrtYd")
		)
		(fp_line
			(start -0.508 0.3048)
			(end -0.508 -0.3048)
			(stroke
				(width 0.1)
				(type default)
			)
			(layer "B.Fab")
		)
		(fp_line
			(start 0.508 0.3048)
			(end -0.508 0.3048)
			(stroke
				(width 0.1)
				(type default)
			)
			(layer "B.Fab")
		)
		(fp_line
			(start -0.508 -0.3048)
			(end 0.508 -0.3048)
			(stroke
				(width 0.1)
				(type default)
			)
			(layer "B.Fab")
		)
		(fp_line
			(start 0.508 -0.3048)
			(end 0.508 0.3048)
			(stroke
				(width 0.1)
				(type default)
			)
			(layer "B.Fab")
		)
		(pad "1" smd rect
			(at 0.5334 0 90)
			(size 0.7112 0.6096)
			(layers "B.Cu" "B.Mask" "B.Paste")
			(net "XP5R0V_USB_CONN_DET")
		)
		(pad "2" smd rect
			(at -0.5334 0 90)
			(size 0.7112 0.6096)
			(layers "B.Cu" "B.Mask" "B.Paste")
			(net "UNNAMED_527_RESISTOR_I201_2")
		)
		(zone
			(layer "B.Cu")
			(hatch none 0.5)
			(connect_pads
				(clearance 0)
			)
			(min_thickness 0.25)
			(keepout
				(tracks allowed)
				(vias not_allowed)
				(pads allowed)
				(copperpour not_allowed)
				(footprints allowed)
			)
			(placement
				(enabled no)
				(sheetname "")
			)
			(fill
				(thermal_gap 0.5)
				(thermal_bridge_width 0.5)
				(island_removal_mode 0)
			)
			(polygon
				(pts
					(xy 159.1818 -50.590196) (xy 158.5722 -50.590196) (xy 158.5722 -50.437796) (xy 159.1818 -50.437796)
				)
			)
		)
	)
)
